(kicad_pcb
	(version 20260206)
	(generator "pcbnew")
	(generator_version "10.0")
	(general
		(thickness 1.6)
		(legacy_teardrops no)
	)
	(paper "A4")
	(title_block
		(title "Bryce Canyon_R.DPB_16317-1_OCP.brd")
		(comment 1 "Bryce Canyon / footprints 119-124 of 2099")
	)
	(layers
		(0 "F.Cu" signal "TOP")
		(4 "In1.Cu" signal "L2GND")
		(6 "In2.Cu" signal "L3")
		(8 "In3.Cu" signal "L4VCC")
		(10 "In4.Cu" signal "L5VCC")
		(12 "In5.Cu" signal "L6")
		(14 "In6.Cu" signal "L7GND")
		(2 "B.Cu" signal "BOTTOM")
		(9 "F.Adhes" user "F.Adhesive")
		(11 "B.Adhes" user "B.Adhesive")
		(13 "F.Paste" user "Package Geometry/Pastemask Top")
		(15 "B.Paste" user "Package Geometry/Pastemask Bottom")
		(5 "F.SilkS" user "Ref Des/Silkscreen Top")
		(7 "B.SilkS" user "Ref Des/Silkscreen Bottom")
		(1 "F.Mask" user "Board Geometry/Soldermask Top")
		(3 "B.Mask" user "Board Geometry/Soldermask Bottom")
		(17 "Dwgs.User" user "User.Drawings")
		(19 "Cmts.User" user "User.Comments")
		(21 "Eco1.User" user "User.Eco1")
		(23 "Eco2.User" user "User.Eco2")
		(25 "Edge.Cuts" user "Board Geometry/Outline")
		(27 "Margin" user)
		(31 "F.CrtYd" user "Package Geometry/Place Bound Top")
		(29 "B.CrtYd" user "Package Geometry/Place Bound Bottom")
		(35 "F.Fab" user "Ref Des/Assembly Top")
		(33 "B.Fab" user "Ref Des/Assembly Bottom")
	)
	(footprint ""
		(layer "F.Cu")
		(at 251.746766 -139.547854)
		(property "Reference" "R464"
			(at 0 0 0)
			(layer "F.SilkS")
			(hide yes)
			(effects
				(font
					(size 1.27 1.27)
				)
			)
		)
		(property "Value" "0R2J-2-GP"
			(at 0.064008 -3.993896 0)
			(unlocked yes)
			(layer "F.Fab")
			(hide yes)
			(effects
				(font
					(size 1.016 1.016)
					(thickness 0.1524)
				)
			)
		)
		(property "Device Type" "R402H16"
			(at 0.064008 -5.517896 0)
			(unlocked yes)
			(layer "F.Fab")
			(hide yes)
			(effects
				(font
					(size 1.016 1.016)
					(thickness 0.1524)
				)
			)
		)
		(duplicate_pad_numbers_are_jumpers no)
		(fp_line
			(start -0.508 -0.9398)
			(end -0.508 0.9398)
			(stroke
				(width 0.1524)
				(type default)
			)
			(layer "F.SilkS")
		)
		(fp_line
			(start 0.508 -0.9398)
			(end -0.508 -0.9398)
			(stroke
				(width 0.1524)
				(type default)
			)
			(layer "F.SilkS")
		)
		(fp_rect
			(start -0.508 0.9398)
			(end 0.508 -0.9398)
			(stroke
				(width 0)
				(type default)
			)
			(fill no)
			(layer "F.CrtYd")
		)
		(fp_rect
			(start -0.508 0.9398)
			(end 0.508 -0.9398)
			(stroke
				(width 0)
				(type default)
			)
			(fill no)
			(layer "F.Fab")
		)
		(pad "1" smd custom
			(at 0 -0.4445)
			(size 0.1397 0.1397)
			(layers "F.Cu" "F.Mask" "F.Paste")
			(net "I2C_SCC_B_SDA_BUF")
			(options
				(clearance outline)
				(anchor circle)
			)
			(primitives
				(gr_poly
					(pts
						(arc
							(start -0.1778 -0.2794)
							(mid -0.249642 -0.249642)
							(end -0.2794 -0.1778)
						)
						(arc
							(start -0.2794 0.1778)
							(mid -0.249642 0.249642)
							(end -0.1778 0.2794)
						)
						(arc
							(start 0.1778 0.2794)
							(mid 0.249642 0.249642)
							(end 0.2794 0.1778)
						)
						(arc
							(start 0.2794 -0.1778)
							(mid 0.249642 -0.249642)
							(end 0.1778 -0.2794)
						)
					)
					(width 0)
					(fill yes)
				)
			)
		)
		(pad "2" smd custom
			(at 0 0.4445)
			(size 0.1397 0.1397)
			(layers "F.Cu" "F.Mask" "F.Paste")
			(net "I2C_SCC_B_SDA")
			(options
				(clearance outline)
				(anchor circle)
			)
			(primitives
				(gr_poly
					(pts
						(arc
							(start -0.1778 -0.2794)
							(mid -0.249642 -0.249642)
							(end -0.2794 -0.1778)
						)
						(arc
							(start -0.2794 0.1778)
							(mid -0.249642 0.249642)
							(end -0.1778 0.2794)
						)
						(arc
							(start 0.1778 0.2794)
							(mid 0.249642 0.249642)
							(end 0.2794 0.1778)
						)
						(arc
							(start 0.2794 -0.1778)
							(mid 0.249642 -0.249642)
							(end 0.1778 -0.2794)
						)
					)
					(width 0)
					(fill yes)
				)
			)
		)
	)
	(footprint ""
		(layer "F.Cu")
		(at 22.987 -245.872 -90)
		(property "Reference" "R908"
			(at 0 0 270)
			(layer "F.SilkS")
			(hide yes)
			(effects
				(font
					(size 1.27 1.27)
				)
			)
		)
		(property "Value" "0R2J-2-GP"
			(at 0.064008 -3.993896 270)
			(unlocked yes)
			(layer "F.Fab")
			(hide yes)
			(effects
				(font
					(size 1.016 1.016)
					(thickness 0.1524)
				)
			)
		)
		(property "Device Type" "R402H16"
			(at 0.064008 -5.517896 270)
			(unlocked yes)
			(layer "F.Fab")
			(hide yes)
			(effects
				(font
					(size 1.016 1.016)
					(thickness 0.1524)
				)
			)
		)
		(duplicate_pad_numbers_are_jumpers no)
		(fp_line
			(start -0.508 -0.9398)
			(end -0.508 0.9398)
			(stroke
				(width 0.1524)
				(type default)
			)
			(layer "F.SilkS")
		)
		(fp_line
			(start 0.508 -0.9398)
			(end -0.508 -0.9398)
			(stroke
				(width 0.1524)
				(type default)
			)
			(layer "F.SilkS")
		)
		(fp_rect
			(start -0.508 0.9398)
			(end 0.508 -0.9398)
			(stroke
				(width 0)
				(type default)
			)
			(fill no)
			(layer "F.CrtYd")
		)
		(fp_rect
			(start -0.508 0.9398)
			(end 0.508 -0.9398)
			(stroke
				(width 0)
				(type default)
			)
			(fill no)
			(layer "F.Fab")
		)
		(pad "1" smd custom
			(at 0 -0.4445 270)
			(size 0.1397 0.1397)
			(layers "F.Cu" "F.Mask" "F.Paste")
			(net "DRIVE_B_0_PWR")
			(options
				(clearance outline)
				(anchor circle)
			)
			(primitives
				(gr_poly
					(pts
						(arc
							(start -0.1778 -0.2794)
							(mid -0.249642 -0.249642)
							(end -0.2794 -0.1778)
						)
						(arc
							(start -0.2794 0.1778)
							(mid -0.249642 0.249642)
							(end -0.1778 0.2794)
						)
						(arc
							(start 0.1778 0.2794)
							(mid 0.249642 0.249642)
							(end 0.2794 0.1778)
						)
						(arc
							(start 0.2794 -0.1778)
							(mid 0.249642 -0.249642)
							(end 0.1778 -0.2794)
						)
					)
					(width 0)
					(fill yes)
				)
			)
		)
		(pad "2" smd custom
			(at 0 0.4445 270)
			(size 0.1397 0.1397)
			(layers "F.Cu" "F.Mask" "F.Paste")
			(net "SW_PWR_R_HDD0")
			(options
				(clearance outline)
				(anchor circle)
			)
			(primitives
				(gr_poly
					(pts
						(arc
							(start -0.1778 -0.2794)
							(mid -0.249642 -0.249642)
							(end -0.2794 -0.1778)
						)
						(arc
							(start -0.2794 0.1778)
							(mid -0.249642 0.249642)
							(end -0.1778 0.2794)
						)
						(arc
							(start 0.1778 0.2794)
							(mid 0.249642 0.249642)
							(end 0.2794 0.1778)
						)
						(arc
							(start 0.2794 -0.1778)
							(mid 0.249642 -0.249642)
							(end 0.1778 -0.2794)
						)
					)
					(width 0)
					(fill yes)
				)
			)
		)
	)
	(footprint ""
		(layer "F.Cu")
		(at 361.315 -275.336 180)
		(property "Reference" "C128"
			(at 0 0 180)
			(layer "F.SilkS")
			(hide yes)
			(effects
				(font
					(size 1.27 1.27)
				)
			)
		)
		(property "Value" "SC1U25V3KX-GP"
			(at 0 -2.8194 180)
			(unlocked yes)
			(layer "F.Fab")
			(hide yes)
			(effects
				(font
					(size 1.016 1.016)
					(thickness 0.1524)
				)
			)
		)
		(property "Device Type" "C603H36"
			(at 0 -4.3434 180)
			(unlocked yes)
			(layer "F.Fab")
			(hide yes)
			(effects
				(font
					(size 1.016 1.016)
					(thickness 0.1524)
				)
			)
		)
		(duplicate_pad_numbers_are_jumpers no)
		(fp_line
			(start 0.508 0)
			(end -0.508 0)
			(stroke
				(width 0.2032)
				(type default)
			)
			(layer "F.SilkS")
		)
		(fp_rect
			(start -0.5842 1.3335)
			(end 0.5842 -1.3335)
			(stroke
				(width 0)
				(type default)
			)
			(fill no)
			(layer "F.CrtYd")
		)
		(fp_rect
			(start -0.5842 1.3335)
			(end 0.5842 -1.3335)
			(stroke
				(width 0)
				(type default)
			)
			(fill no)
			(layer "F.Fab")
		)
		(pad "1" smd custom
			(at 0 -0.762 180)
			(size 0.2159 0.2159)
			(layers "F.Cu" "F.Mask" "F.Paste")
			(net "P12V_HDD7")
			(options
				(clearance outline)
				(anchor circle)
			)
			(primitives
				(gr_poly
					(pts
						(arc
							(start -0.3302 -0.4318)
							(mid -0.402042 -0.402042)
							(end -0.4318 -0.3302)
						)
						(arc
							(start -0.4318 0.3302)
							(mid -0.402042 0.402042)
							(end -0.3302 0.4318)
						)
						(arc
							(start 0.3302 0.4318)
							(mid 0.402042 0.402042)
							(end 0.4318 0.3302)
						)
						(arc
							(start 0.4318 -0.3302)
							(mid 0.402042 -0.402042)
							(end 0.3302 -0.4318)
						)
					)
					(width 0)
					(fill yes)
				)
			)
		)
		(pad "2" smd custom
			(at 0 0.762 180)
			(size 0.2159 0.2159)
			(layers "F.Cu" "F.Mask" "F.Paste")
			(net "GND")
			(options
				(clearance outline)
				(anchor circle)
			)
			(primitives
				(gr_poly
					(pts
						(arc
							(start -0.3302 -0.4318)
							(mid -0.402042 -0.402042)
							(end -0.4318 -0.3302)
						)
						(arc
							(start -0.4318 0.3302)
							(mid -0.402042 0.402042)
							(end -0.3302 0.4318)
						)
						(arc
							(start 0.3302 0.4318)
							(mid 0.402042 0.402042)
							(end 0.4318 0.3302)
						)
						(arc
							(start 0.4318 -0.3302)
							(mid 0.402042 -0.402042)
							(end 0.3302 -0.4318)
						)
					)
					(width 0)
					(fill yes)
				)
			)
		)
	)
	(footprint ""
		(layer "F.Cu")
		(at 461.296004 -376.0978 180)
		(property "Reference" "Q207"
			(at 0 0 180)
			(layer "F.SilkS")
			(hide yes)
			(effects
				(font
					(size 1.27 1.27)
				)
			)
		)
		(property "Value" "SSM6P39TU-GP"
			(at 0.0508 -11.5824 180)
			(unlocked yes)
			(layer "F.Fab")
			(hide yes)
			(effects
				(font
					(size 1.016 1.016)
					(thickness 0.1524)
				)
			)
		)
		(property "Device Type" "UMT6H30"
			(at 0.0508 -13.1572 180)
			(unlocked yes)
			(layer "F.Fab")
			(hide yes)
			(effects
				(font
					(size 1.016 1.016)
					(thickness 0.1524)
				)
			)
		)
		(duplicate_pad_numbers_are_jumpers no)
		(fp_line
			(start 1.524 0.36449)
			(end -1.27 0.36449)
			(stroke
				(width 0.1524)
				(type default)
			)
			(layer "F.SilkS")
		)
		(fp_line
			(start 1.524 -0.36449)
			(end 1.524 0.36449)
			(stroke
				(width 0.1524)
				(type default)
			)
			(layer "F.SilkS")
		)
		(fp_line
			(start 1.524 -0.36449)
			(end 1.524 -1.82245)
			(stroke
				(width 0.508)
				(type default)
			)
			(layer "F.SilkS")
		)
		(fp_line
			(start 1.524 -0.36449)
			(end 1.45796 -0.36449)
			(stroke
				(width 0.1524)
				(type default)
			)
			(layer "F.SilkS")
		)
		(fp_line
			(start 1.45796 -0.36449)
			(end 1.09347 0)
			(stroke
				(width 0.1524)
				(type default)
			)
			(layer "F.SilkS")
		)
		(fp_line
			(start 1.09347 0)
			(end 1.45796 0.36449)
			(stroke
				(width 0.1524)
				(type default)
			)
			(layer "F.SilkS")
		)
		(fp_line
			(start -1.27 -0.36449)
			(end 1.524 -0.36449)
			(stroke
				(width 0.1524)
				(type default)
			)
			(layer "F.SilkS")
		)
		(fp_line
			(start -1.27 -0.36449)
			(end -1.27 0.36449)
			(stroke
				(width 0.1524)
				(type default)
			)
			(layer "F.SilkS")
		)
		(fp_poly
			(pts
				(xy -0.65024 0.36449) (xy -0.65024 -0.36449) (xy 0.65024 -0.36449) (xy 0.65024 0.36449)
			)
			(stroke
				(width 0)
				(type default)
			)
			(fill yes)
			(layer "F.SilkS")
		)
		(fp_poly
			(pts
				(xy 1.016 -1.0668) (xy 1.016 1.0668) (xy -1.016 1.0668) (xy -1.016 -1.0668)
			)
			(stroke
				(width 0)
				(type default)
			)
			(fill no)
			(layer "F.CrtYd")
		)
		(fp_poly
			(pts
				(xy -1.524 1.905) (xy 1.524 1.905) (xy 1.524 -1.06426) (xy 1.016 -1.06426) (xy 1.016 1.0668) (xy -1.016 1.0668)
				(xy -1.016 -1.0668) (xy 1.524 -1.0668) (xy 1.524 -1.905) (xy -1.524 -1.905)
			)
			(stroke
				(width 0)
				(type default)
			)
			(fill no)
			(layer "F.CrtYd")
		)
		(fp_poly
			(pts
				(xy -1.524 -1.905) (xy -1.524 1.905) (xy 1.524 1.905) (xy 1.524 -1.905)
			)
			(stroke
				(width 0)
				(type default)
			)
			(fill no)
			(layer "F.Fab")
		)
		(pad "1" smd rect
			(at 0.65024 -1.02489 180)
			(size 0.4064 0.8128)
			(layers "F.Cu" "F.Mask" "F.Paste")
			(net "P12V_IN")
		)
		(pad "2" smd rect
			(at 0 -1.02489 180)
			(size 0.4064 0.8128)
			(layers "F.Cu" "F.Mask" "F.Paste")
			(net "FAN_YELLOW_LED3")
		)
		(pad "3" smd rect
			(at -0.65024 -1.02489 180)
			(size 0.4064 0.8128)
			(layers "F.Cu" "F.Mask" "F.Paste")
			(net "FAN_BLUE3")
		)
		(pad "4" smd rect
			(at -0.65024 1.02489 180)
			(size 0.4064 0.8128)
			(layers "F.Cu" "F.Mask" "F.Paste")
			(net "P12V_IN")
		)
		(pad "5" smd rect
			(at 0 1.02489 180)
			(size 0.4064 0.8128)
			(layers "F.Cu" "F.Mask" "F.Paste")
			(net "FAN_BLUE_LED3")
		)
		(pad "6" smd rect
			(at 0.65024 1.02489 180)
			(size 0.4064 0.8128)
			(layers "F.Cu" "F.Mask" "F.Paste")
			(net "FAN_YELLOW_3")
		)
	)
	(footprint ""
		(layer "F.Cu")
		(at 265.938 -362.839 180)
		(property "Reference" "Q5"
			(at 0 0 180)
			(layer "F.SilkS")
			(hide yes)
			(effects
				(font
					(size 1.27 1.27)
				)
			)
		)
		(property "Value" "MMBT3904TT1G-GP"
			(at 0 -9.7282 180)
			(unlocked yes)
			(layer "F.Fab")
			(hide yes)
			(effects
				(font
					(size 1.016 1.016)
					(thickness 0.1524)
				)
			)
		)
		(property "Device Type" "SC75CBE1D6H36"
			(at 0 -11.6332 180)
			(unlocked yes)
			(layer "F.Fab")
			(hide yes)
			(effects
				(font
					(size 1.016 1.016)
					(thickness 0.1524)
				)
			)
		)
		(duplicate_pad_numbers_are_jumpers no)
		(fp_line
			(start 0.9652 1.3716)
			(end 0.9652 -1.3716)
			(stroke
				(width 0.1524)
				(type default)
			)
			(layer "F.SilkS")
		)
		(fp_line
			(start 0.9652 -1.3716)
			(end -0.9652 -1.3716)
			(stroke
				(width 0.1524)
				(type default)
			)
			(layer "F.SilkS")
		)
		(fp_line
			(start -0.9652 1.3716)
			(end 0.9652 1.3716)
			(stroke
				(width 0.1524)
				(type default)
			)
			(layer "F.SilkS")
		)
		(fp_line
			(start -0.9652 -1.3716)
			(end -0.9652 1.3716)
			(stroke
				(width 0.1524)
				(type default)
			)
			(layer "F.SilkS")
		)
		(fp_rect
			(start -1.0414 1.4478)
			(end 1.0414 -1.4478)
			(stroke
				(width 0)
				(type default)
			)
			(fill no)
			(layer "F.CrtYd")
		)
		(fp_poly
			(pts
				(xy -1.0414 -1.4478) (xy 1.0414 -1.4478) (xy 1.0414 1.4478) (xy -1.0414 1.4478)
			)
			(stroke
				(width 0)
				(type default)
			)
			(fill no)
			(layer "F.Fab")
		)
		(pad "B" smd custom
			(at -0.508 0.7112 180)
			(size 0.127 0.127)
			(layers "F.Cu" "F.Mask" "F.Paste")
			(net "VCCP_IN")
			(options
				(clearance outline)
				(anchor circle)
			)
			(primitives
				(gr_poly
					(pts
						(arc
							(start -0.044958 0.4572)
							(mid -0.192463 0.399794)
							(end -0.254 0.254)
						)
						(xy -0.254 -0.254)
						(arc
							(start -0.253746 -0.254)
							(mid -0.192968 -0.398936)
							(end -0.04699 -0.4572)
						)
						(arc
							(start 0.04699 -0.4572)
							(mid 0.192989 -0.398958)
							(end 0.253746 -0.254)
						)
						(xy 0.254 -0.254)
						(arc
							(start 0.254 0.254)
							(mid 0.192404 0.399734)
							(end 0.044958 0.4572)
						)
					)
					(width 0)
					(fill yes)
				)
			)
		)
		(pad "C" smd custom
			(at 0 -0.7112 180)
			(size 0.127 0.127)
			(layers "F.Cu" "F.Mask" "F.Paste")
			(net "P12V_IN")
			(options
				(clearance outline)
				(anchor circle)
			)
			(primitives
				(gr_poly
					(pts
						(arc
							(start -0.044958 0.4572)
							(mid -0.192463 0.399794)
							(end -0.254 0.254)
						)
						(xy -0.254 -0.254)
						(arc
							(start -0.253746 -0.254)
							(mid -0.192968 -0.398936)
							(end -0.04699 -0.4572)
						)
						(arc
							(start 0.04699 -0.4572)
							(mid 0.192989 -0.398958)
							(end 0.253746 -0.254)
						)
						(xy 0.254 -0.254)
						(arc
							(start 0.254 0.254)
							(mid 0.192404 0.399734)
							(end 0.044958 0.4572)
						)
					)
					(width 0)
					(fill yes)
				)
			)
		)
		(pad "E" smd custom
			(at 0.508 0.7112 180)
			(size 0.127 0.127)
			(layers "F.Cu" "F.Mask" "F.Paste")
			(net "P3V3_IN_BIAS")
			(options
				(clearance outline)
				(anchor circle)
			)
			(primitives
				(gr_poly
					(pts
						(arc
							(start -0.044958 0.4572)
							(mid -0.192463 0.399794)
							(end -0.254 0.254)
						)
						(xy -0.254 -0.254)
						(arc
							(start -0.253746 -0.254)
							(mid -0.192968 -0.398936)
							(end -0.04699 -0.4572)
						)
						(arc
							(start 0.04699 -0.4572)
							(mid 0.192989 -0.398958)
							(end 0.253746 -0.254)
						)
						(xy 0.254 -0.254)
						(arc
							(start 0.254 0.254)
							(mid 0.192404 0.399734)
							(end 0.044958 0.4572)
						)
					)
					(width 0)
					(fill yes)
				)
			)
		)
	)
	(footprint ""
		(layer "F.Cu")
		(at 209.775298 -224.651062 90)
		(property "Reference" "R19"
			(at 0 0 90)
			(layer "F.SilkS")
			(hide yes)
			(effects
				(font
					(size 1.27 1.27)
				)
			)
		)
		(property "Value" "4K7R2F-GP"
			(at 0.064008 -3.993896 90)
			(unlocked yes)
			(layer "F.Fab")
			(hide yes)
			(effects
				(font
					(size 1.016 1.016)
					(thickness 0.1524)
				)
			)
		)
		(property "Device Type" "R402H16"
			(at 0.064008 -5.517896 90)
			(unlocked yes)
			(layer "F.Fab")
			(hide yes)
			(effects
				(font
					(size 1.016 1.016)
					(thickness 0.1524)
				)
			)
		)
		(duplicate_pad_numbers_are_jumpers no)
		(fp_line
			(start 0.508 -0.9398)
			(end -0.508 -0.9398)
			(stroke
				(width 0.1524)
				(type default)
			)
			(layer "F.SilkS")
		)
		(fp_line
			(start -0.508 -0.9398)
			(end -0.508 0.9398)
			(stroke
				(width 0.1524)
				(type default)
			)
			(layer "F.SilkS")
		)
		(fp_rect
			(start -0.508 0.9398)
			(end 0.508 -0.9398)
			(stroke
				(width 0)
				(type default)
			)
			(fill no)
			(layer "F.CrtYd")
		)
		(fp_rect
			(start -0.508 0.9398)
			(end 0.508 -0.9398)
			(stroke
				(width 0)
				(type default)
			)
			(fill no)
			(layer "F.Fab")
		)
		(pad "1" smd custom
			(at 0 -0.4445 90)
			(size 0.1397 0.1397)
			(layers "F.Cu" "F.Mask" "F.Paste")
			(net "P3V3_STBY_B")
			(options
				(clearance outline)
				(anchor circle)
			)
			(primitives
				(gr_poly
					(pts
						(arc
							(start -0.1778 -0.2794)
							(mid -0.249642 -0.249642)
							(end -0.2794 -0.1778)
						)
						(arc
							(start -0.2794 0.1778)
							(mid -0.249642 0.249642)
							(end -0.1778 0.2794)
						)
						(arc
							(start 0.1778 0.2794)
							(mid 0.249642 0.249642)
							(end 0.2794 0.1778)
						)
						(arc
							(start 0.2794 -0.1778)
							(mid 0.249642 -0.249642)
							(end 0.1778 -0.2794)
						)
					)
					(width 0)
					(fill yes)
				)
			)
		)
		(pad "2" smd custom
			(at 0 0.4445 90)
			(size 0.1397 0.1397)
			(layers "F.Cu" "F.Mask" "F.Paste")
			(net "IO_EXP1_HDD_FAULT_A2")
			(options
				(clearance outline)
				(anchor circle)
			)
			(primitives
				(gr_poly
					(pts
						(arc
							(start -0.1778 -0.2794)
							(mid -0.249642 -0.249642)
							(end -0.2794 -0.1778)
						)
						(arc
							(start -0.2794 0.1778)
							(mid -0.249642 0.249642)
							(end -0.1778 0.2794)
						)
						(arc
							(start 0.1778 0.2794)
							(mid 0.249642 0.249642)
							(end 0.2794 0.1778)
						)
						(arc
							(start 0.2794 -0.1778)
							(mid 0.249642 -0.249642)
							(end 0.1778 -0.2794)
						)
					)
					(width 0)
					(fill yes)
				)
			)
		)
	)
)
